# S9S_MB_2U (Grand Teton) — schematic netlist excerpt (pin names and nets, part order shuffled) for the footprints in the layout excerpt that follows; sources: Cadence DE-HDL packaged netlist, KiCad conversion of 03242023_DA0F0TMBIJ0_F0T_Motherboard_J_brd_V01_OCP.brd

R2367  Q_RES  10K 1% EMPTY  pkg 0402LF  page 299 : A = P3V3_AUX ; B = FM_PVPP_HBM_CPU1_EN
C1918  Q_CAP  0.01UF 50V 10% X7R  pkg C0402  page 217 : A = P3V3_AUX_FPGA_VCCIO1 ; B = GND

(kicad_pcb
	(version 20260206)
	(generator "pcbnew")
	(generator_version "10.0")
	(general
		(thickness 1.6)
		(legacy_teardrops no)
	)
	(paper "A4")
	(title_block
		(title "03242023_DA0F0TMBIJ0_F0T_Motherboard_J_brd_V01_OCP.brd")
		(comment 1 "Grand Teton / footprints 5570-5571 of 6105")
	)
	(layers
		(0 "F.Cu" signal "TOP")
		(4 "In1.Cu" signal "GND")
		(6 "In2.Cu" signal "IN1")
		(8 "In3.Cu" signal "GND1")
		(10 "In4.Cu" signal "IN2")
		(12 "In5.Cu" signal "GND2")
		(14 "In6.Cu" signal "IN3")
		(16 "In7.Cu" signal "GND3")
		(18 "In8.Cu" signal "VCC")
		(20 "In9.Cu" signal "VCC1")
		(22 "In10.Cu" signal "GND4")
		(24 "In11.Cu" signal "IN4")
		(26 "In12.Cu" signal "GND5")
		(28 "In13.Cu" signal "IN5")
		(30 "In14.Cu" signal "GND6")
		(32 "In15.Cu" signal "IN6")
		(34 "In16.Cu" signal "GND7")
		(2 "B.Cu" signal "BOTTOM")
		(9 "F.Adhes" user "F.Adhesive")
		(11 "B.Adhes" user "B.Adhesive")
		(13 "F.Paste" user "Package Geometry/Pastemask Top")
		(15 "B.Paste" user "Package Geometry/Pastemask Bottom")
		(5 "F.SilkS" user "Ref Des/Silkscreen Top")
		(7 "B.SilkS" user "Ref Des/Silkscreen Bottom")
		(1 "F.Mask" user "Board Geometry/Soldermask Top")
		(3 "B.Mask" user "Board Geometry/Soldermask Bottom")
		(17 "Dwgs.User" user "User.Drawings")
		(19 "Cmts.User" user "User.Comments")
		(21 "Eco1.User" user "User.Eco1")
		(23 "Eco2.User" user "User.Eco2")
		(25 "Edge.Cuts" user "Board Geometry/Outline")
		(27 "Margin" user)
		(31 "F.CrtYd" user "Package Geometry/Place Bound Top")
		(29 "B.CrtYd" user "Package Geometry/Place Bound Bottom")
		(35 "F.Fab" user "Ref Des/Assembly Top")
		(33 "B.Fab" user "Ref Des/Assembly Bottom")
	)
	(footprint ""
		(layer "B.Cu")
		(at 121.773442 -356.200456 180)
		(property "Reference" "R2367"
			(at 0 0 0)
			(layer "B.SilkS")
			(hide yes)
			(effects
				(font
					(size 1.27 1.27)
				)
				(justify mirror)
			)
		)
		(property "Value" ""
			(at 0 0 0)
			(layer "B.Fab")
			(effects
				(font
					(size 1.27 1.27)
				)
				(justify mirror)
			)
		)
		(duplicate_pad_numbers_are_jumpers no)
		(fp_line
			(start 0.7874 0.4064)
			(end 0.7874 -0.4064)
			(stroke
				(width 0.1524)
				(type default)
			)
			(layer "B.SilkS")
		)
		(fp_line
			(start 0.7874 -0.4064)
			(end -0.7874 -0.4064)
			(stroke
				(width 0.1524)
				(type default)
			)
			(layer "B.SilkS")
		)
		(fp_line
			(start -0.7874 0.4064)
			(end 0.7874 0.4064)
			(stroke
				(width 0.1524)
				(type default)
			)
			(layer "B.SilkS")
		)
		(fp_line
			(start -0.7874 -0.4064)
			(end -0.7874 0.4064)
			(stroke
				(width 0.1524)
				(type default)
			)
			(layer "B.SilkS")
		)
		(fp_line
			(start 0.67945 0.3048)
			(end 0.67945 -0.305054)
			(stroke
				(width 0.1)
				(type default)
			)
			(layer "B.Fab")
		)
		(fp_line
			(start 0.67945 -0.305054)
			(end 0.12065 -0.305054)
			(stroke
				(width 0.1)
				(type default)
			)
			(layer "B.Fab")
		)
		(fp_line
			(start 0.12065 0.3048)
			(end 0.67945 0.3048)
			(stroke
				(width 0.1)
				(type default)
			)
			(layer "B.Fab")
		)
		(fp_line
			(start 0.12065 0.2794)
			(end 0.12065 0.3048)
			(stroke
				(width 0.1)
				(type default)
			)
			(layer "B.Fab")
		)
		(fp_line
			(start 0.12065 -0.2794)
			(end -0.12065 -0.2794)
			(stroke
				(width 0.1)
				(type default)
			)
			(layer "B.Fab")
		)
		(fp_line
			(start 0.12065 -0.305054)
			(end 0.12065 -0.2794)
			(stroke
				(width 0.1)
				(type default)
			)
			(layer "B.Fab")
		)
		(fp_line
			(start -0.120396 0.3048)
			(end -0.120396 0.2794)
			(stroke
				(width 0.1)
				(type default)
			)
			(layer "B.Fab")
		)
		(fp_line
			(start -0.120396 0.2794)
			(end 0.12065 0.2794)
			(stroke
				(width 0.1)
				(type default)
			)
			(layer "B.Fab")
		)
		(fp_line
			(start -0.12065 -0.2794)
			(end -0.12065 -0.3048)
			(stroke
				(width 0.1)
				(type default)
			)
			(layer "B.Fab")
		)
		(fp_line
			(start -0.12065 -0.3048)
			(end -0.67945 -0.3048)
			(stroke
				(width 0.1)
				(type default)
			)
			(layer "B.Fab")
		)
		(fp_line
			(start -0.67945 0.3048)
			(end -0.120396 0.3048)
			(stroke
				(width 0.1)
				(type default)
			)
			(layer "B.Fab")
		)
		(fp_line
			(start -0.67945 -0.3048)
			(end -0.67945 0.3048)
			(stroke
				(width 0.1)
				(type default)
			)
			(layer "B.Fab")
		)
		(pad "1" smd circle
			(at 0.40005 0)
			(size 0 0)
			(layers "B.Cu" "B.Mask" "B.Paste")
			(net "P3V3_AUX")
		)
		(pad "2" smd circle
			(at -0.40005 0)
			(size 0 0)
			(layers "B.Cu" "B.Mask" "B.Paste")
			(net "FM_PVPP_HBM_CPU1_EN")
		)
	)
	(footprint ""
		(layer "B.Cu")
		(at 178.9557 -115.775486 90)
		(property "Reference" "C1918"
			(at 0 0 90)
			(layer "B.SilkS")
			(hide yes)
			(effects
				(font
					(size 1.27 1.27)
				)
				(justify mirror)
			)
		)
		(property "Value" ""
			(at 0 0 90)
			(layer "B.Fab")
			(effects
				(font
					(size 1.27 1.27)
				)
				(justify mirror)
			)
		)
		(duplicate_pad_numbers_are_jumpers no)
		(fp_line
			(start 0.69215 -0.2921)
			(end -0.69215 -0.2921)
			(stroke
				(width 0.1524)
				(type default)
			)
			(layer "B.SilkS")
		)
		(fp_line
			(start -0.69215 -0.2921)
			(end -0.69215 0.2921)
			(stroke
				(width 0.1524)
				(type default)
			)
			(layer "B.SilkS")
		)
		(fp_line
			(start 0.69215 0.2921)
			(end 0.69215 -0.2921)
			(stroke
				(width 0.1524)
				(type default)
			)
			(layer "B.SilkS")
		)
		(fp_line
			(start -0.69215 0.2921)
			(end 0.69215 0.2921)
			(stroke
				(width 0.1524)
				(type default)
			)
			(layer "B.SilkS")
		)
		(fp_line
			(start 0.51435 -0.2794)
			(end -0.51435 -0.2794)
			(stroke
				(width 0.1)
				(type default)
			)
			(layer "B.Fab")
		)
		(fp_line
			(start -0.51435 -0.2794)
			(end -0.51435 0.2794)
			(stroke
				(width 0.1)
				(type default)
			)
			(layer "B.Fab")
		)
		(fp_line
			(start 0.51435 0.2794)
			(end 0.51435 -0.2794)
			(stroke
				(width 0.1)
				(type default)
			)
			(layer "B.Fab")
		)
		(fp_line
			(start -0.51435 0.2794)
			(end 0.51435 0.2794)
			(stroke
				(width 0.1)
				(type default)
			)
			(layer "B.Fab")
		)
		(pad "1" smd circle
			(at 0.40005 0 270)
			(size 0 0)
			(layers "B.Cu" "B.Mask" "B.Paste")
			(net "P3V3_AUX_FPGA_VCCIO1")
		)
		(pad "2" smd circle
			(at -0.40005 0 270)
			(size 0 0)
			(layers "B.Cu" "B.Mask" "B.Paste")
			(net "GND")
		)
		(zone
			(layer "B.Cu")
			(hatch none 0.5)
			(connect_pads
				(clearance 0)
			)
			(min_thickness 0.25)
			(keepout
				(tracks not_allowed)
				(vias allowed)
				(pads allowed)
				(copperpour not_allowed)
				(footprints allowed)
			)
			(placement
				(enabled no)
				(sheetname "")
			)
			(fill
				(thermal_gap 0.5)
				(thermal_bridge_width 0.5)
				(island_removal_mode 0)
			)
			(polygon
				(pts
					(xy 179.04333 -115.965986) (xy 179.101496 -115.874546) (xy 179.101496 -115.675156) (xy 179.04333 -115.584986)
					(xy 178.86807 -115.584986) (xy 178.80965 -115.675156) (xy 178.80965 -115.874546) (xy 178.867816 -115.965986)
				)
			)
		)
	)
)
